# BASEBOARD_FAB2 (Tioga Pass) — schematic netlist excerpt (pin names and nets, part order shuffled) for the footprints in the layout excerpt that follows; sources: Cadence DE-HDL packaged netlist, KiCad conversion of Wiwynn_Tioga_Pass_MB.brd

C4C12  CAPP  270UF 16V 20% OSCON  pkg 2626  page 204 : A = VR_FET_SW_P12V_STBY_PVCCIN_CPU0 ; B = GND
C9G13  CAP  4700PF 50V 10% EMPTY  pkg 0402LF  page 141 : A = NIC_SET_N_MDI_2_DN ; B = NIC_MDI_MNG_TX_DN

(kicad_pcb
	(version 20260206)
	(generator "pcbnew")
	(generator_version "10.0")
	(general
		(thickness 1.6)
		(legacy_teardrops no)
	)
	(paper "A4")
	(title_block
		(title "Wiwynn_Tioga_Pass_MB.brd")
		(comment 1 "Tioga Pass / footprints 1799-1800 of 4770")
	)
	(layers
		(0 "F.Cu" signal "TOP")
		(4 "In1.Cu" signal "L2GND")
		(6 "In2.Cu" signal "L3")
		(8 "In3.Cu" signal "L4GND")
		(10 "In4.Cu" signal "L5")
		(12 "In5.Cu" signal "L6GND")
		(14 "In6.Cu" signal "L7VCC")
		(16 "In7.Cu" signal "L8VCC")
		(18 "In8.Cu" signal "L9GND")
		(20 "In9.Cu" signal "L10")
		(22 "In10.Cu" signal "L11GND")
		(24 "In11.Cu" signal "L12")
		(26 "In12.Cu" signal "L13GND")
		(2 "B.Cu" signal "BOTTOM")
		(9 "F.Adhes" user "F.Adhesive")
		(11 "B.Adhes" user "B.Adhesive")
		(13 "F.Paste" user "Package Geometry/Pastemask Top")
		(15 "B.Paste" user "Package Geometry/Pastemask Bottom")
		(5 "F.SilkS" user "Ref Des/Silkscreen Top")
		(7 "B.SilkS" user "Ref Des/Silkscreen Bottom")
		(1 "F.Mask" user "Board Geometry/Soldermask Top")
		(3 "B.Mask" user "Board Geometry/Soldermask Bottom")
		(17 "Dwgs.User" user "User.Drawings")
		(19 "Cmts.User" user "User.Comments")
		(21 "Eco1.User" user "User.Eco1")
		(23 "Eco2.User" user "User.Eco2")
		(25 "Edge.Cuts" user "Board Geometry/Outline")
		(27 "Margin" user)
		(31 "F.CrtYd" user "Package Geometry/Place Bound Top")
		(29 "B.CrtYd" user "Package Geometry/Place Bound Bottom")
		(35 "F.Fab" user "Ref Des/Assembly Top")
		(33 "B.Fab" user "Ref Des/Assembly Bottom")
	)
	(footprint ""
		(layer "F.Cu")
		(at 190.754 -94.107 -90)
		(property "Reference" "C4C12"
			(at 1.905 7.84733 90)
			(unlocked yes)
			(layer "F.SilkS")
			(effects
				(font
					(size 0.7874 0.5842)
					(thickness 0.1524)
				)
				(justify left)
			)
		)
		(property "Value" ""
			(at 0 0 270)
			(layer "F.Fab")
			(effects
				(font
					(size 1.27 1.27)
				)
			)
		)
		(duplicate_pad_numbers_are_jumpers no)
		(fp_line
			(start -3.400044 6.067044)
			(end -0.9017 6.067044)
			(stroke
				(width 0.1524)
				(type default)
			)
			(layer "F.SilkS")
		)
		(fp_line
			(start 0.9017 6.067044)
			(end 3.400044 6.067044)
			(stroke
				(width 0.1524)
				(type default)
			)
			(layer "F.SilkS")
		)
		(fp_line
			(start 3.400044 6.067044)
			(end 3.400044 0.028956)
			(stroke
				(width 0.1524)
				(type default)
			)
			(layer "F.SilkS")
		)
		(fp_line
			(start -0.9017 1.587754)
			(end -0.7239 1.587754)
			(stroke
				(width 0.1524)
				(type default)
			)
			(layer "F.SilkS")
		)
		(fp_line
			(start 0.7239 1.587754)
			(end 0.9017 1.587754)
			(stroke
				(width 0.1524)
				(type default)
			)
			(layer "F.SilkS")
		)
		(fp_line
			(start 0.9017 1.587754)
			(end 0.9017 -1.714246)
			(stroke
				(width 0.1524)
				(type default)
			)
			(layer "F.SilkS")
		)
		(fp_line
			(start -3.400044 0.028956)
			(end -3.400044 6.067044)
			(stroke
				(width 0.1524)
				(type default)
			)
			(layer "F.SilkS")
		)
		(fp_line
			(start 3.400044 0.028956)
			(end 2.638044 -0.733044)
			(stroke
				(width 0.1524)
				(type default)
			)
			(layer "F.SilkS")
		)
		(fp_line
			(start -2.638044 -0.733044)
			(end -3.400044 0.028956)
			(stroke
				(width 0.1524)
				(type default)
			)
			(layer "F.SilkS")
		)
		(fp_line
			(start -0.9017 -0.733044)
			(end -2.638044 -0.733044)
			(stroke
				(width 0.1524)
				(type default)
			)
			(layer "F.SilkS")
		)
		(fp_line
			(start 2.638044 -0.733044)
			(end 0.9017 -0.733044)
			(stroke
				(width 0.1524)
				(type default)
			)
			(layer "F.SilkS")
		)
		(fp_line
			(start -0.9017 -1.714246)
			(end -0.9017 1.587754)
			(stroke
				(width 0.1524)
				(type default)
			)
			(layer "F.SilkS")
		)
		(fp_line
			(start -0.7239 -1.714246)
			(end -0.9017 -1.714246)
			(stroke
				(width 0.1524)
				(type default)
			)
			(layer "F.SilkS")
		)
		(fp_line
			(start 0.9017 -1.714246)
			(end 0.7239 -1.714246)
			(stroke
				(width 0.1524)
				(type default)
			)
			(layer "F.SilkS")
		)
		(fp_poly
			(pts
				(xy -3.400044 6.067044) (xy 3.400044 6.067044) (xy 3.400044 0.028956) (xy 2.638044 -0.733044) (xy -2.638044 -0.733044)
				(xy -3.400044 0.028956)
			)
			(stroke
				(width 0)
				(type default)
			)
			(fill no)
			(layer "F.CrtYd")
		)
		(fp_line
			(start -3.400044 6.067044)
			(end 3.400044 6.067044)
			(stroke
				(width 0.1)
				(type default)
			)
			(layer "F.Fab")
		)
		(fp_line
			(start 3.400044 6.067044)
			(end 3.400044 0.028956)
			(stroke
				(width 0.1)
				(type default)
			)
			(layer "F.Fab")
		)
		(fp_line
			(start -3.400044 0.028956)
			(end -3.400044 6.067044)
			(stroke
				(width 0.1)
				(type default)
			)
			(layer "F.Fab")
		)
		(fp_line
			(start 3.400044 0.028956)
			(end 2.638044 -0.733044)
			(stroke
				(width 0.1)
				(type default)
			)
			(layer "F.Fab")
		)
		(fp_line
			(start -2.638044 -0.733044)
			(end -3.400044 0.028956)
			(stroke
				(width 0.1)
				(type default)
			)
			(layer "F.Fab")
		)
		(fp_line
			(start 2.638044 -0.733044)
			(end -2.638044 -0.733044)
			(stroke
				(width 0.1)
				(type default)
			)
			(layer "F.Fab")
		)
		(fp_circle
			(center 0 2.667)
			(end 0 -0.733044)
			(stroke
				(width 0.1)
				(type default)
			)
			(fill no)
			(layer "F.Fab")
		)
		(pad "1" smd rect
			(at 0 0 270)
			(size 0.7874 3.429)
			(layers "F.Cu" "F.Mask" "F.Paste")
			(net "VR_FET_SW_P12V_STBY_PVCCIN_CPU0")
		)
		(pad "2" smd rect
			(at 0 5.334 270)
			(size 0.7874 3.429)
			(layers "F.Cu" "F.Mask" "F.Paste")
			(net "GND")
		)
	)
	(footprint ""
		(layer "F.Cu")
		(at 480.845876 3.820668 90)
		(property "Reference" "C9G13"
			(at 0 0 90)
			(layer "F.SilkS")
			(hide yes)
			(effects
				(font
					(size 1.27 1.27)
				)
			)
		)
		(property "Value" ""
			(at 0 0 90)
			(layer "F.Fab")
			(effects
				(font
					(size 1.27 1.27)
				)
			)
		)
		(duplicate_pad_numbers_are_jumpers no)
		(fp_poly
			(pts
				(xy 0.3048 -0.1016) (xy 0.3048 0.9906) (xy -0.3048 0.9906) (xy -0.3048 -0.1016)
			)
			(stroke
				(width 0)
				(type default)
			)
			(fill no)
			(layer "F.CrtYd")
		)
		(fp_line
			(start 0.3048 -0.1016)
			(end -0.3048 -0.1016)
			(stroke
				(width 0.1)
				(type default)
			)
			(layer "F.Fab")
		)
		(fp_line
			(start -0.3048 -0.1016)
			(end -0.3048 0.9906)
			(stroke
				(width 0.1)
				(type default)
			)
			(layer "F.Fab")
		)
		(fp_line
			(start 0.3048 0.9906)
			(end 0.3048 -0.1016)
			(stroke
				(width 0.1)
				(type default)
			)
			(layer "F.Fab")
		)
		(fp_line
			(start -0.3048 0.9906)
			(end 0.3048 0.9906)
			(stroke
				(width 0.1)
				(type default)
			)
			(layer "F.Fab")
		)
		(pad "1" smd rect
			(at 0 0 90)
			(size 0.508 0.508)
			(layers "F.Cu" "F.Mask" "F.Paste")
			(net "NIC_SET_N_MDI_2_DN")
		)
		(pad "2" smd rect
			(at 0 0.889 90)
			(size 0.508 0.508)
			(layers "F.Cu" "F.Mask" "F.Paste")
			(net "NIC_MDI_MNG_TX_DN")
		)
		(zone
			(layer "F.Cu")
			(hatch none 0.5)
			(connect_pads
				(clearance 0)
			)
			(min_thickness 0.25)
			(keepout
				(tracks allowed)
				(vias not_allowed)
				(pads allowed)
				(copperpour not_allowed)
				(footprints allowed)
			)
			(placement
				(enabled no)
				(sheetname "")
			)
			(fill
				(thermal_gap 0.5)
				(thermal_bridge_width 0.5)
				(island_removal_mode 0)
			)
			(polygon
				(pts
					(xy 481.099876 4.074668) (xy 481.099876 3.566668) (xy 481.480876 3.566668) (xy 481.480876 4.074668)
				)
			)
		)
		(zone
			(layer "F.Cu")
			(hatch none 0.5)
			(connect_pads
				(clearance 0)
			)
			(min_thickness 0.25)
			(keepout
				(tracks not_allowed)
				(vias allowed)
				(pads allowed)
				(copperpour not_allowed)
				(footprints allowed)
			)
			(placement
				(enabled no)
				(sheetname "")
			)
			(fill
				(thermal_gap 0.5)
				(thermal_bridge_width 0.5)
				(island_removal_mode 0)
			)
			(polygon
				(pts
					(xy 481.480876 4.074668) (xy 481.480876 3.566668) (xy 481.099876 3.566668) (xy 481.099876 4.074668)
				)
			)
		)
	)
)
